(kicad_pcb
	(version 20241229)
	(generator "pcbnew")
	(generator_version "9.0")
	(general
		(thickness 1.6642)
		(legacy_teardrops no)
	)
	(paper "A3")
	(title_block
		(title "PolarFire SoM")
		(date "2025-07-22")
		(rev "1.1.4")
		(company "Antmicro Ltd")
		(comment 1 "www.antmicro.com")
		(comment 9 "footprints 149-152 of 470")
	)
	(layers
		(0 "F.Cu" mixed)
		(4 "In1.Cu" power)
		(6 "In2.Cu" signal)
		(8 "In3.Cu" power)
		(10 "In4.Cu" signal)
		(12 "In5.Cu" power)
		(14 "In6.Cu" power)
		(16 "In7.Cu" signal)
		(18 "In8.Cu" power)
		(20 "In9.Cu" signal)
		(22 "In10.Cu" power)
		(24 "In11.Cu" signal)
		(26 "In12.Cu" signal)
		(2 "B.Cu" mixed)
		(9 "F.Adhes" user "F.Adhesive")
		(11 "B.Adhes" user "B.Adhesive")
		(13 "F.Paste" user)
		(15 "B.Paste" user)
		(5 "F.SilkS" user "F.Silkscreen")
		(7 "B.SilkS" user "B.Silkscreen")
		(1 "F.Mask" user)
		(3 "B.Mask" user)
		(17 "Dwgs.User" user "User.Drawings")
		(19 "Cmts.User" user "User.Comments")
		(21 "Eco1.User" user "User.Eco1")
		(23 "Eco2.User" user "User.Eco2")
		(25 "Edge.Cuts" user)
		(27 "Margin" user)
		(31 "F.CrtYd" user "F.Courtyard")
		(29 "B.CrtYd" user "B.Courtyard")
		(35 "F.Fab" user)
		(33 "B.Fab" user)
	)
	(footprint "antmicro-footprints:C_0402_1005Metric"
		(layer "B.Cu")
		(at 184.85 135.325 90)
		(descr "Capacitor SMD 0402")
		(tags "capacitor SMD 0402")
		(property "Reference" "C159"
			(at -1.3 1.225 270)
			(layer "B.SilkS")
			(effects
				(font
					(size 0.7 0.7)
					(thickness 0.15)
				)
				(justify right bottom mirror)
			)
		)
		(property "Value" "C_1u_0402"
			(at -1.022927 -2.155213 90)
			(layer "B.Fab")
			(hide yes)
			(effects
				(font
					(size 0.7 0.7)
					(thickness 0.15)
				)
				(justify right bottom mirror)
			)
		)
		(property "Datasheet" "https://product.tdk.com/en/search/capacitor/ceramic/mlcc/info?part_no=C1005X6S1A105K050BC"
			(at 0 0 90)
			(layer "F.Fab")
			(hide yes)
			(effects
				(font
					(size 1.27 1.27)
					(thickness 0.15)
				)
			)
		)
		(property "Description" "SMD Multilayer Ceramic Capacitor, 1 µF, 10 V, 0402 [1005 Metric], ± 10%, X6S, C"
			(at 0 0 90)
			(layer "F.Fab")
			(hide yes)
			(effects
				(font
					(size 1.27 1.27)
					(thickness 0.15)
				)
			)
		)
		(property "Author" "Antmicro"
			(at 320.175 -49.525 0)
			(layer "B.Fab")
			(hide yes)
			(effects
				(font
					(size 1 1)
					(thickness 0.15)
				)
				(justify mirror)
			)
		)
		(property "Dielectric" "X5R"
			(at 320.175 -49.525 0)
			(layer "B.Fab")
			(hide yes)
			(effects
				(font
					(size 1 1)
					(thickness 0.15)
				)
				(justify mirror)
			)
		)
		(property "License" "Apache-2.0"
			(at 320.175 -49.525 0)
			(layer "B.Fab")
			(hide yes)
			(effects
				(font
					(size 1 1)
					(thickness 0.15)
				)
				(justify mirror)
			)
		)
		(property "MPN" "C1005X6S1A105K050BC"
			(at 320.175 -49.525 0)
			(layer "B.Fab")
			(hide yes)
			(effects
				(font
					(size 1 1)
					(thickness 0.15)
				)
				(justify mirror)
			)
		)
		(property "Manufacturer" "TDK"
			(at 320.175 -49.525 0)
			(layer "B.Fab")
			(hide yes)
			(effects
				(font
					(size 1 1)
					(thickness 0.15)
				)
				(justify mirror)
			)
		)
		(property "Public" ""
			(at 320.175 -49.525 0)
			(layer "B.Fab")
			(hide yes)
			(effects
				(font
					(size 1 1)
					(thickness 0.15)
				)
				(justify mirror)
			)
		)
		(property "Val" "1u"
			(at 320.175 -49.525 0)
			(layer "B.Fab")
			(hide yes)
			(effects
				(font
					(size 1 1)
					(thickness 0.15)
				)
				(justify mirror)
			)
		)
		(property "Voltage" "16V"
			(at 320.175 -49.525 0)
			(layer "B.Fab")
			(hide yes)
			(effects
				(font
					(size 1 1)
					(thickness 0.15)
				)
				(justify mirror)
			)
		)
		(sheetname "/LPDDR4/")
		(sheetfile "lpddr.kicad_sch")
		(attr smd)
		(fp_rect
			(start -0.925 0.47)
			(end 0.925 -0.47)
			(stroke
				(width 0.05)
				(type default)
			)
			(fill no)
			(layer "B.CrtYd")
		)
		(fp_line
			(start 0.504 -0.248)
			(end -0.494 -0.248)
			(stroke
				(width 0.15)
				(type solid)
			)
			(layer "B.Fab")
		)
		(fp_line
			(start -0.494 -0.248)
			(end -0.494 0.25)
			(stroke
				(width 0.15)
				(type solid)
			)
			(layer "B.Fab")
		)
		(fp_line
			(start 0.504 0.25)
			(end 0.504 -0.248)
			(stroke
				(width 0.15)
				(type solid)
			)
			(layer "B.Fab")
		)
		(fp_line
			(start -0.494 0.25)
			(end 0.504 0.25)
			(stroke
				(width 0.15)
				(type solid)
			)
			(layer "B.Fab")
		)
		(fp_text user "Author: Antmicro"
			(at -0.939 -3.399 270)
			(layer "B.Fab")
			(effects
				(font
					(size 0.7 0.7)
					(thickness 0.15)
				)
				(justify left bottom mirror)
			)
		)
		(fp_text user "${REFERENCE}"
			(at -0.939 -4.599 270)
			(layer "B.Fab")
			(effects
				(font
					(size 0.7 0.7)
					(thickness 0.15)
				)
				(justify left bottom mirror)
			)
		)
		(fp_text user "License: Apache-2.0"
			(at -0.939 -5.799 270)
			(layer "B.Fab")
			(effects
				(font
					(size 0.7 0.7)
					(thickness 0.15)
				)
				(justify left bottom mirror)
			)
		)
		(pad "1" smd roundrect
			(at -0.48 0 90)
			(size 0.59 0.64)
			(layers "B.Cu" "B.Mask" "B.Paste")
			(roundrect_rratio 0.25)
			(net 417 "GND")
			(pintype "passive")
		)
		(pad "2" smd roundrect
			(at 0.48 0 90)
			(size 0.59 0.64)
			(layers "B.Cu" "B.Mask" "B.Paste")
			(roundrect_rratio 0.25)
			(net 2 "+1V1")
			(pintype "passive")
		)
	)
	(footprint "antmicro-footprints:SOT-583"
		(layer "B.Cu")
		(at 222.175 136 -90)
		(property "Reference" "U10"
			(at -0.55 1.35 90)
			(layer "B.SilkS")
			(effects
				(font
					(size 0.7 0.7)
					(thickness 0.15)
				)
				(justify left bottom mirror)
			)
		)
		(property "Value" "TPS2117DRLR"
			(at 0 -2.3 90)
			(layer "B.Fab")
			(hide yes)
			(effects
				(font
					(size 0.7 0.7)
					(thickness 0.15)
				)
				(justify left bottom mirror)
			)
		)
		(property "Datasheet" "https://www.ti.com/lit/ds/symlink/tps2117.pdf"
			(at 0 0 270)
			(layer "F.Fab")
			(hide yes)
			(effects
				(font
					(size 1.27 1.27)
					(thickness 0.15)
				)
			)
		)
		(property "Description" "TPS2117 1.6-V to 5.5-V, 4-A Low IQ Power Mux With Manual and Priority Switchover"
			(at 0 0 270)
			(layer "F.Fab")
			(hide yes)
			(effects
				(font
					(size 1.27 1.27)
					(thickness 0.15)
				)
			)
		)
		(property "Author" "Antmicro"
			(at 86.175 358.175 0)
			(layer "B.Fab")
			(hide yes)
			(effects
				(font
					(size 1 1)
					(thickness 0.15)
				)
				(justify mirror)
			)
		)
		(property "License" "Apache-2.0"
			(at 86.175 358.175 0)
			(layer "B.Fab")
			(hide yes)
			(effects
				(font
					(size 1 1)
					(thickness 0.15)
				)
				(justify mirror)
			)
		)
		(property "MPN" "TPS2117DRLR"
			(at 86.175 358.175 0)
			(layer "B.Fab")
			(hide yes)
			(effects
				(font
					(size 1 1)
					(thickness 0.15)
				)
				(justify mirror)
			)
		)
		(property "Manufacturer" "Texas Instruments"
			(at 86.175 358.175 0)
			(layer "B.Fab")
			(hide yes)
			(effects
				(font
					(size 1 1)
					(thickness 0.15)
				)
				(justify mirror)
			)
		)
		(property ki_fp_filters "DRL0008A-MFG")
		(sheetname "/Memory/")
		(sheetfile "memory.kicad_sch")
		(attr smd)
		(fp_line
			(start -0.65 1.15)
			(end 0.65 1.15)
			(stroke
				(width 0.15)
				(type solid)
			)
			(layer "B.SilkS")
		)
		(fp_line
			(start -0.651 -1.15)
			(end 0.651 -1.15)
			(stroke
				(width 0.15)
				(type solid)
			)
			(layer "B.SilkS")
		)
		(fp_circle
			(center -0.9 1.1)
			(end -0.85 1.05)
			(stroke
				(width 0.15)
				(type solid)
			)
			(fill yes)
			(layer "B.SilkS")
		)
		(fp_rect
			(start -1.15 1.3)
			(end 1.15 -1.3)
			(stroke
				(width 0.05)
				(type solid)
			)
			(fill no)
			(layer "B.CrtYd")
		)
		(fp_line
			(start -0.651 1.1005)
			(end 0.651 1.1005)
			(stroke
				(width 0.15)
				(type solid)
			)
			(layer "B.Fab")
		)
		(fp_line
			(start -0.651 -1.1005)
			(end -0.651 1.1005)
			(stroke
				(width 0.15)
				(type solid)
			)
			(layer "B.Fab")
		)
		(fp_line
			(start -0.651 -1.1005)
			(end 0.651 -1.1005)
			(stroke
				(width 0.15)
				(type solid)
			)
			(layer "B.Fab")
		)
		(fp_line
			(start 0.651 -1.1005)
			(end 0.651 1.1005)
			(stroke
				(width 0.15)
				(type solid)
			)
			(layer "B.Fab")
		)
		(fp_text user "License: Apache-2.0"
			(at -0.06 -6.025 90)
			(layer "B.Fab")
			(effects
				(font
					(size 0.7 0.7)
					(thickness 0.15)
				)
				(justify left bottom mirror)
			)
		)
		(fp_text user "Author: Antmicro"
			(at -0.06 -5.025 90)
			(layer "B.Fab")
			(effects
				(font
					(size 0.7 0.7)
					(thickness 0.15)
				)
				(justify left bottom mirror)
			)
		)
		(fp_text user "${REFERENCE}"
			(at -0.06 -4.025 90)
			(layer "B.Fab")
			(effects
				(font
					(size 0.7 0.7)
					(thickness 0.15)
				)
				(justify left bottom mirror)
			)
		)
		(pad "1" smd roundrect
			(at -0.739 0.7495 270)
			(size 0.670001 0.299999)
			(layers "B.Cu" "B.Mask" "B.Paste")
			(roundrect_rratio 0.25)
			(net 417 "GND")
			(pinfunction "GND")
			(pintype "power_in")
		)
		(pad "2" smd roundrect
			(at -0.739 0.2505 270)
			(size 0.670001 0.299999)
			(layers "B.Cu" "B.Mask" "B.Paste")
			(roundrect_rratio 0.25)
			(net 518 "Net-(R56-Pad1)")
			(pinfunction "VOUT")
			(pintype "power_out")
		)
		(pad "3" smd roundrect
			(at -0.739 -0.2495 270)
			(size 0.670001 0.299999)
			(layers "B.Cu" "B.Mask" "B.Paste")
			(roundrect_rratio 0.25)
			(net 418 "+2V5")
			(pinfunction "VIN1")
			(pintype "power_in")
		)
		(pad "4" smd roundrect
			(at -0.739 -0.7495 270)
			(size 0.670001 0.299999)
			(layers "B.Cu" "B.Mask" "B.Paste")
			(roundrect_rratio 0.25)
			(net 246 "SD_VDD_OVERRIDE")
			(pinfunction "PR1")
			(pintype "input")
		)
		(pad "5" smd roundrect
			(at 0.74 -0.7495 270)
			(size 0.670001 0.299999)
			(layers "B.Cu" "B.Mask" "B.Paste")
			(roundrect_rratio 0.25)
			(net 50 "+3V3")
			(pinfunction "MODE")
			(pintype "input")
		)
		(pad "6" smd roundrect
			(at 0.74 -0.2495 270)
			(size 0.670001 0.299999)
			(layers "B.Cu" "B.Mask" "B.Paste")
			(roundrect_rratio 0.25)
			(net 50 "+3V3")
			(pinfunction "VIN2")
			(pintype "power_in")
		)
		(pad "7" smd roundrect
			(at 0.74 0.2505 270)
			(size 0.670001 0.299999)
			(layers "B.Cu" "B.Mask" "B.Paste")
			(roundrect_rratio 0.25)
			(net 518 "Net-(R56-Pad1)")
			(pinfunction "VOUT")
			(pintype "passive")
		)
		(pad "8" smd roundrect
			(at 0.74 0.7495 270)
			(size 0.670001 0.299999)
			(layers "B.Cu" "B.Mask" "B.Paste")
			(roundrect_rratio 0.25)
			(net 523 "unconnected-(U10-ST-Pad8)")
			(pinfunction "ST")
			(pintype "output+no_connect")
		)
	)
	(footprint "antmicro-footprints:C_0402_1005Metric"
		(layer "B.Cu")
		(at 222.43 152.76)
		(descr "Capacitor SMD 0402")
		(tags "capacitor SMD 0402")
		(property "Reference" "C3"
			(at 0.96 1.74 0)
			(layer "B.SilkS")
			(effects
				(font
					(size 0.7 0.7)
					(thickness 0.15)
				)
				(justify right bottom mirror)
			)
		)
		(property "Value" "C_100n_0402"
			(at -1.022927 -2.155213 0)
			(layer "B.Fab")
			(hide yes)
			(effects
				(font
					(size 0.7 0.7)
					(thickness 0.15)
				)
				(justify right bottom mirror)
			)
		)
		(property "Datasheet" "https://www.murata.com/products/productdetail?partno=GRM155R61H104KE14%23"
			(at 0 0 0)
			(layer "F.Fab")
			(hide yes)
			(effects
				(font
					(size 1.27 1.27)
					(thickness 0.15)
				)
			)
		)
		(property "Description" "SMD Multilayer Ceramic Capacitor, 0.1 µF, 50 V, 0402 [1005 Metric], ± 10%, X5R, GRM Series"
			(at 0 0 0)
			(layer "F.Fab")
			(hide yes)
			(effects
				(font
					(size 1.27 1.27)
					(thickness 0.15)
				)
			)
		)
		(property "Author" "Antmicro"
			(at 0 0 0)
			(layer "B.Fab")
			(hide yes)
			(effects
				(font
					(size 1 1)
					(thickness 0.15)
				)
				(justify mirror)
			)
		)
		(property "Dielectric" "X5R"
			(at 0 0 0)
			(layer "B.Fab")
			(hide yes)
			(effects
				(font
					(size 1 1)
					(thickness 0.15)
				)
				(justify mirror)
			)
		)
		(property "License" "Apache-2.0"
			(at 0 0 0)
			(layer "B.Fab")
			(hide yes)
			(effects
				(font
					(size 1 1)
					(thickness 0.15)
				)
				(justify mirror)
			)
		)
		(property "MPN" "GRM155R61H104KE14D"
			(at 0 0 0)
			(layer "B.Fab")
			(hide yes)
			(effects
				(font
					(size 1 1)
					(thickness 0.15)
				)
				(justify mirror)
			)
		)
		(property "Manufacturer" "Murata"
			(at 0 0 0)
			(layer "B.Fab")
			(hide yes)
			(effects
				(font
					(size 1 1)
					(thickness 0.15)
				)
				(justify mirror)
			)
		)
		(property "Public" ""
			(at 0 0 0)
			(layer "B.Fab")
			(hide yes)
			(effects
				(font
					(size 1 1)
					(thickness 0.15)
				)
				(justify mirror)
			)
		)
		(property "Val" "100n"
			(at 0 0 0)
			(layer "B.Fab")
			(hide yes)
			(effects
				(font
					(size 1 1)
					(thickness 0.15)
				)
				(justify mirror)
			)
		)
		(property "Voltage" "50V"
			(at 0 0 0)
			(layer "B.Fab")
			(hide yes)
			(effects
				(font
					(size 1 1)
					(thickness 0.15)
				)
				(justify mirror)
			)
		)
		(sheetname "/PCIe/")
		(sheetfile "pcie.kicad_sch")
		(attr smd)
		(fp_rect
			(start -0.925 0.47)
			(end 0.925 -0.47)
			(stroke
				(width 0.05)
				(type default)
			)
			(fill no)
			(layer "B.CrtYd")
		)
		(fp_line
			(start -0.494 -0.248)
			(end -0.494 0.25)
			(stroke
				(width 0.15)
				(type solid)
			)
			(layer "B.Fab")
		)
		(fp_line
			(start -0.494 0.25)
			(end 0.504 0.25)
			(stroke
				(width 0.15)
				(type solid)
			)
			(layer "B.Fab")
		)
		(fp_line
			(start 0.504 -0.248)
			(end -0.494 -0.248)
			(stroke
				(width 0.15)
				(type solid)
			)
			(layer "B.Fab")
		)
		(fp_line
			(start 0.504 0.25)
			(end 0.504 -0.248)
			(stroke
				(width 0.15)
				(type solid)
			)
			(layer "B.Fab")
		)
		(fp_text user "Author: Antmicro"
			(at -0.939 -3.399 180)
			(layer "B.Fab")
			(effects
				(font
					(size 0.7 0.7)
					(thickness 0.15)
				)
				(justify left bottom mirror)
			)
		)
		(fp_text user "${REFERENCE}"
			(at -0.939 -4.599 180)
			(layer "B.Fab")
			(effects
				(font
					(size 0.7 0.7)
					(thickness 0.15)
				)
				(justify left bottom mirror)
			)
		)
		(fp_text user "License: Apache-2.0"
			(at -0.939 -5.799 180)
			(layer "B.Fab")
			(effects
				(font
					(size 0.7 0.7)
					(thickness 0.15)
				)
				(justify left bottom mirror)
			)
		)
		(pad "1" smd roundrect
			(at -0.48 0)
			(size 0.59 0.64)
			(layers "B.Cu" "B.Mask" "B.Paste")
			(roundrect_rratio 0.25)
			(net 417 "GND")
			(pintype "passive")
		)
		(pad "2" smd roundrect
			(at 0.48 0)
			(size 0.59 0.64)
			(layers "B.Cu" "B.Mask" "B.Paste")
			(roundrect_rratio 0.25)
			(net 418 "+2V5")
			(pintype "passive")
		)
	)
	(footprint "antmicro-footprints:C_0402_1005Metric"
		(layer "B.Cu")
		(at 204.5 135.01 90)
		(descr "Capacitor SMD 0402")
		(tags "capacitor SMD 0402")
		(property "Reference" "C57"
			(at 1.01 0.5 90)
			(layer "B.SilkS")
			(effects
				(font
					(size 0.7 0.7)
					(thickness 0.15)
				)
				(justify right bottom mirror)
			)
		)
		(property "Value" "C_4n7_0402"
			(at -1.022927 -2.155213 90)
			(layer "B.Fab")
			(hide yes)
			(effects
				(font
					(size 0.7 0.7)
					(thickness 0.15)
				)
				(justify right bottom mirror)
			)
		)
		(property "Datasheet" "https://product.tdk.com/en/search/capacitor/ceramic/mlcc/info?part_no=CGA2B3X7S2A472K050BB"
			(at 0 0 90)
			(layer "F.Fab")
			(hide yes)
			(effects
				(font
					(size 1.27 1.27)
					(thickness 0.15)
				)
			)
		)
		(property "Description" "SMD Multilayer Ceramic Capacitor, 4700 pF, 100 V, 0402 [1005 Metric], ± 10%, X7S, CGA"
			(at 0 0 90)
			(layer "F.Fab")
			(hide yes)
			(effects
				(font
					(size 1.27 1.27)
					(thickness 0.15)
				)
			)
		)
		(property "Author" "Antmicro"
			(at 339.51 -69.49 0)
			(layer "B.Fab")
			(hide yes)
			(effects
				(font
					(size 1 1)
					(thickness 0.15)
				)
				(justify mirror)
			)
		)
		(property "Dielectric" "X7R"
			(at 339.51 -69.49 0)
			(layer "B.Fab")
			(hide yes)
			(effects
				(font
					(size 1 1)
					(thickness 0.15)
				)
				(justify mirror)
			)
		)
		(property "License" "Apache-2.0"
			(at 339.51 -69.49 0)
			(layer "B.Fab")
			(hide yes)
			(effects
				(font
					(size 1 1)
					(thickness 0.15)
				)
				(justify mirror)
			)
		)
		(property "MPN" "CGA2B3X7S2A472K050BB"
			(at 339.51 -69.49 0)
			(layer "B.Fab")
			(hide yes)
			(effects
				(font
					(size 1 1)
					(thickness 0.15)
				)
				(justify mirror)
			)
		)
		(property "Manufacturer" "TDK"
			(at 339.51 -69.49 0)
			(layer "B.Fab")
			(hide yes)
			(effects
				(font
					(size 1 1)
					(thickness 0.15)
				)
				(justify mirror)
			)
		)
		(property "Public" ""
			(at 339.51 -69.49 0)
			(layer "B.Fab")
			(hide yes)
			(effects
				(font
					(size 1 1)
					(thickness 0.15)
				)
				(justify mirror)
			)
		)
		(property "Val" "4n7"
			(at 339.51 -69.49 0)
			(layer "B.Fab")
			(hide yes)
			(effects
				(font
					(size 1 1)
					(thickness 0.15)
				)
				(justify mirror)
			)
		)
		(property "Voltage" "25V"
			(at 339.51 -69.49 0)
			(layer "B.Fab")
			(hide yes)
			(effects
				(font
					(size 1 1)
					(thickness 0.15)
				)
				(justify mirror)
			)
		)
		(sheetname "/FPGA Supply/")
		(sheetfile "fpga-supply.kicad_sch")
		(attr smd)
		(fp_rect
			(start -0.925 0.47)
			(end 0.925 -0.47)
			(stroke
				(width 0.05)
				(type default)
			)
			(fill no)
			(layer "B.CrtYd")
		)
		(fp_line
			(start 0.504 -0.248)
			(end -0.494 -0.248)
			(stroke
				(width 0.15)
				(type solid)
			)
			(layer "B.Fab")
		)
		(fp_line
			(start -0.494 -0.248)
			(end -0.494 0.25)
			(stroke
				(width 0.15)
				(type solid)
			)
			(layer "B.Fab")
		)
		(fp_line
			(start 0.504 0.25)
			(end 0.504 -0.248)
			(stroke
				(width 0.15)
				(type solid)
			)
			(layer "B.Fab")
		)
		(fp_line
			(start -0.494 0.25)
			(end 0.504 0.25)
			(stroke
				(width 0.15)
				(type solid)
			)
			(layer "B.Fab")
		)
		(fp_text user "Author: Antmicro"
			(at -0.939 -3.399 270)
			(layer "B.Fab")
			(effects
				(font
					(size 0.7 0.7)
					(thickness 0.15)
				)
				(justify left bottom mirror)
			)
		)
		(fp_text user "License: Apache-2.0"
			(at -0.939 -5.799 270)
			(layer "B.Fab")
			(effects
				(font
					(size 0.7 0.7)
					(thickness 0.15)
				)
				(justify left bottom mirror)
			)
		)
		(fp_text user "${REFERENCE}"
			(at -0.939 -4.599 270)
			(layer "B.Fab")
			(effects
				(font
					(size 0.7 0.7)
					(thickness 0.15)
				)
				(justify left bottom mirror)
			)
		)
		(pad "1" smd roundrect
			(at -0.48 0 90)
			(size 0.59 0.64)
			(layers "B.Cu" "B.Mask" "B.Paste")
			(roundrect_rratio 0.25)
			(net 417 "GND")
			(pintype "passive")
		)
		(pad "2" smd roundrect
			(at 0.48 0 90)
			(size 0.59 0.64)
			(layers "B.Cu" "B.Mask" "B.Paste")
			(roundrect_rratio 0.25)
			(net 649 "VDD")
			(pintype "passive")
		)
	)
)
